# SCM (Grand Teton) — schematic netlist excerpt (pin names and nets, part order shuffled) for the footprints in the layout excerpt that follows; sources: Cadence DE-HDL packaged netlist, KiCad conversion of 12092022_DA0F0TMDCD0_F0T_Management_Board_D_brd_V3_OCP.brd

R686  Q_RES  4.7K 1% EMPTY  pkg 0402LF  page 14 : A = P3V3_AUX ; B = BMC_EMMC_WP_N
R282  Q_RES  0 5% CHIP  pkg 0402LF  page 22 : A = RST_BMC_HW_R1 ; B = RST_BMC_HW

(kicad_pcb
	(version 20260206)
	(generator "pcbnew")
	(generator_version "10.0")
	(general
		(thickness 1.6)
		(legacy_teardrops no)
	)
	(paper "A4")
	(title_block
		(title "12092022_DA0F0TMDCD0_F0T_Management_Board_D_brd_V3_OCP.brd")
		(comment 1 "Grand Teton / footprints 769-770 of 1440")
	)
	(layers
		(0 "F.Cu" signal "TOP")
		(4 "In1.Cu" signal "GND")
		(6 "In2.Cu" signal "IN1")
		(8 "In3.Cu" signal "GND1")
		(10 "In4.Cu" signal "IN2")
		(12 "In5.Cu" signal "VCC")
		(14 "In6.Cu" signal "VCC1")
		(16 "In7.Cu" signal "IN3")
		(18 "In8.Cu" signal "GND2")
		(20 "In9.Cu" signal "IN4")
		(22 "In10.Cu" signal "GND3")
		(2 "B.Cu" signal "BOTTOM")
		(9 "F.Adhes" user "F.Adhesive")
		(11 "B.Adhes" user "B.Adhesive")
		(13 "F.Paste" user "Package Geometry/Pastemask Top")
		(15 "B.Paste" user "Package Geometry/Pastemask Bottom")
		(5 "F.SilkS" user "Ref Des/Silkscreen Top")
		(7 "B.SilkS" user "Ref Des/Silkscreen Bottom")
		(1 "F.Mask" user "Board Geometry/Soldermask Top")
		(3 "B.Mask" user "Board Geometry/Soldermask Bottom")
		(17 "Dwgs.User" user "User.Drawings")
		(19 "Cmts.User" user "User.Comments")
		(21 "Eco1.User" user "User.Eco1")
		(23 "Eco2.User" user "User.Eco2")
		(25 "Edge.Cuts" user "Board Geometry/Outline")
		(27 "Margin" user)
		(31 "F.CrtYd" user "Package Geometry/Place Bound Top")
		(29 "B.CrtYd" user "Package Geometry/Place Bound Bottom")
		(35 "F.Fab" user "Ref Des/Assembly Top")
		(33 "B.Fab" user "Ref Des/Assembly Bottom")
	)
	(footprint ""
		(layer "B.Cu")
		(at 72.621394 -69.576188 -90)
		(property "Reference" "R686"
			(at 0 0 90)
			(layer "B.SilkS")
			(hide yes)
			(effects
				(font
					(size 1.27 1.27)
				)
				(justify mirror)
			)
		)
		(property "Value" ""
			(at 0 0 90)
			(layer "B.Fab")
			(effects
				(font
					(size 1.27 1.27)
				)
				(justify mirror)
			)
		)
		(duplicate_pad_numbers_are_jumpers no)
		(fp_line
			(start -0.7874 0.4064)
			(end 0.7874 0.4064)
			(stroke
				(width 0.1524)
				(type default)
			)
			(layer "B.SilkS")
		)
		(fp_line
			(start 0.7874 0.4064)
			(end 0.7874 -0.4064)
			(stroke
				(width 0.1524)
				(type default)
			)
			(layer "B.SilkS")
		)
		(fp_line
			(start -0.7874 -0.4064)
			(end -0.7874 0.4064)
			(stroke
				(width 0.1524)
				(type default)
			)
			(layer "B.SilkS")
		)
		(fp_line
			(start 0.7874 -0.4064)
			(end -0.7874 -0.4064)
			(stroke
				(width 0.1524)
				(type default)
			)
			(layer "B.SilkS")
		)
		(fp_line
			(start -0.67945 0.3048)
			(end -0.120396 0.3048)
			(stroke
				(width 0.1)
				(type default)
			)
			(layer "B.Fab")
		)
		(fp_line
			(start -0.120396 0.3048)
			(end -0.120396 0.2794)
			(stroke
				(width 0.1)
				(type default)
			)
			(layer "B.Fab")
		)
		(fp_line
			(start 0.12065 0.3048)
			(end 0.67945 0.3048)
			(stroke
				(width 0.1)
				(type default)
			)
			(layer "B.Fab")
		)
		(fp_line
			(start 0.67945 0.3048)
			(end 0.67945 -0.305054)
			(stroke
				(width 0.1)
				(type default)
			)
			(layer "B.Fab")
		)
		(fp_line
			(start -0.120396 0.2794)
			(end 0.12065 0.2794)
			(stroke
				(width 0.1)
				(type default)
			)
			(layer "B.Fab")
		)
		(fp_line
			(start 0.12065 0.2794)
			(end 0.12065 0.3048)
			(stroke
				(width 0.1)
				(type default)
			)
			(layer "B.Fab")
		)
		(fp_line
			(start -0.12065 -0.2794)
			(end -0.12065 -0.3048)
			(stroke
				(width 0.1)
				(type default)
			)
			(layer "B.Fab")
		)
		(fp_line
			(start 0.12065 -0.2794)
			(end -0.12065 -0.2794)
			(stroke
				(width 0.1)
				(type default)
			)
			(layer "B.Fab")
		)
		(fp_line
			(start -0.67945 -0.3048)
			(end -0.67945 0.3048)
			(stroke
				(width 0.1)
				(type default)
			)
			(layer "B.Fab")
		)
		(fp_line
			(start -0.12065 -0.3048)
			(end -0.67945 -0.3048)
			(stroke
				(width 0.1)
				(type default)
			)
			(layer "B.Fab")
		)
		(fp_line
			(start 0.12065 -0.305054)
			(end 0.12065 -0.2794)
			(stroke
				(width 0.1)
				(type default)
			)
			(layer "B.Fab")
		)
		(fp_line
			(start 0.67945 -0.305054)
			(end 0.12065 -0.305054)
			(stroke
				(width 0.1)
				(type default)
			)
			(layer "B.Fab")
		)
		(pad "1" smd circle
			(at 0.40005 0 90)
			(size 0 0)
			(layers "B.Cu" "B.Mask" "B.Paste")
			(net "P3V3_AUX")
		)
		(pad "2" smd circle
			(at -0.40005 0 90)
			(size 0 0)
			(layers "B.Cu" "B.Mask" "B.Paste")
			(net "BMC_EMMC_WP_N")
		)
	)
	(footprint ""
		(layer "B.Cu")
		(at 33.02 -101.854 -90)
		(property "Reference" "R282"
			(at 0 0 90)
			(layer "B.SilkS")
			(hide yes)
			(effects
				(font
					(size 1.27 1.27)
				)
				(justify mirror)
			)
		)
		(property "Value" ""
			(at 0 0 90)
			(layer "B.Fab")
			(effects
				(font
					(size 1.27 1.27)
				)
				(justify mirror)
			)
		)
		(duplicate_pad_numbers_are_jumpers no)
		(fp_line
			(start -0.7874 0.4064)
			(end 0.7874 0.4064)
			(stroke
				(width 0.1524)
				(type default)
			)
			(layer "B.SilkS")
		)
		(fp_line
			(start 0.7874 0.4064)
			(end 0.7874 -0.4064)
			(stroke
				(width 0.1524)
				(type default)
			)
			(layer "B.SilkS")
		)
		(fp_line
			(start -0.7874 -0.4064)
			(end -0.7874 0.4064)
			(stroke
				(width 0.1524)
				(type default)
			)
			(layer "B.SilkS")
		)
		(fp_line
			(start 0.7874 -0.4064)
			(end -0.7874 -0.4064)
			(stroke
				(width 0.1524)
				(type default)
			)
			(layer "B.SilkS")
		)
		(fp_line
			(start -0.67945 0.3048)
			(end -0.120396 0.3048)
			(stroke
				(width 0.1)
				(type default)
			)
			(layer "B.Fab")
		)
		(fp_line
			(start -0.120396 0.3048)
			(end -0.120396 0.2794)
			(stroke
				(width 0.1)
				(type default)
			)
			(layer "B.Fab")
		)
		(fp_line
			(start 0.12065 0.3048)
			(end 0.67945 0.3048)
			(stroke
				(width 0.1)
				(type default)
			)
			(layer "B.Fab")
		)
		(fp_line
			(start 0.67945 0.3048)
			(end 0.67945 -0.305054)
			(stroke
				(width 0.1)
				(type default)
			)
			(layer "B.Fab")
		)
		(fp_line
			(start -0.120396 0.2794)
			(end 0.12065 0.2794)
			(stroke
				(width 0.1)
				(type default)
			)
			(layer "B.Fab")
		)
		(fp_line
			(start 0.12065 0.2794)
			(end 0.12065 0.3048)
			(stroke
				(width 0.1)
				(type default)
			)
			(layer "B.Fab")
		)
		(fp_line
			(start -0.12065 -0.2794)
			(end -0.12065 -0.3048)
			(stroke
				(width 0.1)
				(type default)
			)
			(layer "B.Fab")
		)
		(fp_line
			(start 0.12065 -0.2794)
			(end -0.12065 -0.2794)
			(stroke
				(width 0.1)
				(type default)
			)
			(layer "B.Fab")
		)
		(fp_line
			(start -0.67945 -0.3048)
			(end -0.67945 0.3048)
			(stroke
				(width 0.1)
				(type default)
			)
			(layer "B.Fab")
		)
		(fp_line
			(start -0.12065 -0.3048)
			(end -0.67945 -0.3048)
			(stroke
				(width 0.1)
				(type default)
			)
			(layer "B.Fab")
		)
		(fp_line
			(start 0.12065 -0.305054)
			(end 0.12065 -0.2794)
			(stroke
				(width 0.1)
				(type default)
			)
			(layer "B.Fab")
		)
		(fp_line
			(start 0.67945 -0.305054)
			(end 0.12065 -0.305054)
			(stroke
				(width 0.1)
				(type default)
			)
			(layer "B.Fab")
		)
		(pad "1" smd circle
			(at 0.40005 0 90)
			(size 0 0)
			(layers "B.Cu" "B.Mask" "B.Paste")
			(net "RST_BMC_HW_R1")
		)
		(pad "2" smd circle
			(at -0.40005 0 90)
			(size 0 0)
			(layers "B.Cu" "B.Mask" "B.Paste")
			(net "RST_BMC_HW")
		)
	)
)
